(kicad_pcb
	(version 20260206)
	(generator "pcbnew")
	(generator_version "10.0")
	(general
		(thickness 1.6)
		(legacy_teardrops no)
	)
	(paper "A4")
	(title_block
		(title "01162023_DA0F0TEBIF0_F0T_Expander_BD_F_brd_V02_OCP.brd")
		(comment 1 "Grand Teton / footprints 6330-6335 of 9728")
	)
	(layers
		(0 "F.Cu" signal "TOP")
		(4 "In1.Cu" signal "GND")
		(6 "In2.Cu" signal "VCC")
		(8 "In3.Cu" signal "VCC1")
		(10 "In4.Cu" signal "GND1")
		(12 "In5.Cu" signal "IN1")
		(14 "In6.Cu" signal "GND2")
		(16 "In7.Cu" signal "IN2")
		(18 "In8.Cu" signal "GND3")
		(20 "In9.Cu" signal "IN3")
		(22 "In10.Cu" signal "GND4")
		(24 "In11.Cu" signal "IN4")
		(26 "In12.Cu" signal "GND5")
		(28 "In13.Cu" signal "IN5")
		(30 "In14.Cu" signal "GND6")
		(32 "In15.Cu" signal "IN6")
		(34 "In16.Cu" signal "GND7")
		(2 "B.Cu" signal "BOTTOM")
		(9 "F.Adhes" user "F.Adhesive")
		(11 "B.Adhes" user "B.Adhesive")
		(13 "F.Paste" user "Package Geometry/Pastemask Top")
		(15 "B.Paste" user "Package Geometry/Pastemask Bottom")
		(5 "F.SilkS" user "Ref Des/Silkscreen Top")
		(7 "B.SilkS" user "Ref Des/Silkscreen Bottom")
		(1 "F.Mask" user "Board Geometry/Soldermask Top")
		(3 "B.Mask" user "Board Geometry/Soldermask Bottom")
		(17 "Dwgs.User" user "User.Drawings")
		(19 "Cmts.User" user "User.Comments")
		(21 "Eco1.User" user "User.Eco1")
		(23 "Eco2.User" user "User.Eco2")
		(25 "Edge.Cuts" user "Board Geometry/Outline")
		(27 "Margin" user)
		(31 "F.CrtYd" user "Package Geometry/Place Bound Top")
		(29 "B.CrtYd" user "Package Geometry/Place Bound Bottom")
		(35 "F.Fab" user "Ref Des/Assembly Top")
		(33 "B.Fab" user "Ref Des/Assembly Bottom")
	)
	(footprint ""
		(layer "F.Cu")
		(at 407.295096 -97.718372 180)
		(property "Reference" "R405"
			(at 0 0 180)
			(layer "F.SilkS")
			(hide yes)
			(effects
				(font
					(size 1.27 1.27)
				)
			)
		)
		(property "Value" ""
			(at 0 0 180)
			(layer "F.Fab")
			(effects
				(font
					(size 1.27 1.27)
				)
			)
		)
		(duplicate_pad_numbers_are_jumpers no)
		(fp_line
			(start 0.7874 0.4064)
			(end -0.7874 0.4064)
			(stroke
				(width 0.1524)
				(type default)
			)
			(layer "F.SilkS")
		)
		(fp_line
			(start 0.7874 -0.4064)
			(end 0.7874 0.4064)
			(stroke
				(width 0.1524)
				(type default)
			)
			(layer "F.SilkS")
		)
		(fp_line
			(start -0.7874 0.4064)
			(end -0.7874 -0.4064)
			(stroke
				(width 0.1524)
				(type default)
			)
			(layer "F.SilkS")
		)
		(fp_line
			(start -0.7874 -0.4064)
			(end 0.7874 -0.4064)
			(stroke
				(width 0.1524)
				(type default)
			)
			(layer "F.SilkS")
		)
		(fp_line
			(start 0.67945 0.3048)
			(end 0.120396 0.3048)
			(stroke
				(width 0.1)
				(type default)
			)
			(layer "F.Fab")
		)
		(fp_line
			(start 0.67945 -0.3048)
			(end 0.67945 0.3048)
			(stroke
				(width 0.1)
				(type default)
			)
			(layer "F.Fab")
		)
		(fp_line
			(start 0.12065 -0.2794)
			(end 0.12065 -0.3048)
			(stroke
				(width 0.1)
				(type default)
			)
			(layer "F.Fab")
		)
		(fp_line
			(start 0.12065 -0.3048)
			(end 0.67945 -0.3048)
			(stroke
				(width 0.1)
				(type default)
			)
			(layer "F.Fab")
		)
		(fp_line
			(start 0.120396 0.3048)
			(end 0.120396 0.2794)
			(stroke
				(width 0.1)
				(type default)
			)
			(layer "F.Fab")
		)
		(fp_line
			(start 0.120396 0.2794)
			(end -0.12065 0.2794)
			(stroke
				(width 0.1)
				(type default)
			)
			(layer "F.Fab")
		)
		(fp_line
			(start -0.12065 0.3048)
			(end -0.67945 0.3048)
			(stroke
				(width 0.1)
				(type default)
			)
			(layer "F.Fab")
		)
		(fp_line
			(start -0.12065 0.2794)
			(end -0.12065 0.3048)
			(stroke
				(width 0.1)
				(type default)
			)
			(layer "F.Fab")
		)
		(fp_line
			(start -0.12065 -0.2794)
			(end 0.12065 -0.2794)
			(stroke
				(width 0.1)
				(type default)
			)
			(layer "F.Fab")
		)
		(fp_line
			(start -0.12065 -0.305054)
			(end -0.12065 -0.2794)
			(stroke
				(width 0.1)
				(type default)
			)
			(layer "F.Fab")
		)
		(fp_line
			(start -0.67945 0.3048)
			(end -0.67945 -0.305054)
			(stroke
				(width 0.1)
				(type default)
			)
			(layer "F.Fab")
		)
		(fp_line
			(start -0.67945 -0.305054)
			(end -0.12065 -0.305054)
			(stroke
				(width 0.1)
				(type default)
			)
			(layer "F.Fab")
		)
		(pad "1" smd circle
			(at -0.40005 0 180)
			(size 0 0)
			(layers "F.Cu" "F.Mask" "F.Paste")
			(net "RST_NIC7_PERST3_R_N")
		)
		(pad "2" smd circle
			(at 0.40005 0 180)
			(size 0 0)
			(layers "F.Cu" "F.Mask" "F.Paste")
			(net "RST_HP_NIC7_BUF_N")
		)
	)
	(footprint ""
		(layer "F.Cu")
		(at 400.759422 -22.955504 90)
		(property "Reference" "R1728"
			(at 0 0 90)
			(layer "F.SilkS")
			(hide yes)
			(effects
				(font
					(size 1.27 1.27)
				)
			)
		)
		(property "Value" ""
			(at 0 0 90)
			(layer "F.Fab")
			(effects
				(font
					(size 1.27 1.27)
				)
			)
		)
		(duplicate_pad_numbers_are_jumpers no)
		(fp_line
			(start 0.7874 -0.4064)
			(end 0.7874 0.4064)
			(stroke
				(width 0.1524)
				(type default)
			)
			(layer "F.SilkS")
		)
		(fp_line
			(start -0.7874 -0.4064)
			(end 0.7874 -0.4064)
			(stroke
				(width 0.1524)
				(type default)
			)
			(layer "F.SilkS")
		)
		(fp_line
			(start 0.7874 0.4064)
			(end -0.7874 0.4064)
			(stroke
				(width 0.1524)
				(type default)
			)
			(layer "F.SilkS")
		)
		(fp_line
			(start -0.7874 0.4064)
			(end -0.7874 -0.4064)
			(stroke
				(width 0.1524)
				(type default)
			)
			(layer "F.SilkS")
		)
		(fp_line
			(start -0.12065 -0.305054)
			(end -0.12065 -0.2794)
			(stroke
				(width 0.1)
				(type default)
			)
			(layer "F.Fab")
		)
		(fp_line
			(start -0.67945 -0.305054)
			(end -0.12065 -0.305054)
			(stroke
				(width 0.1)
				(type default)
			)
			(layer "F.Fab")
		)
		(fp_line
			(start 0.67945 -0.3048)
			(end 0.67945 0.3048)
			(stroke
				(width 0.1)
				(type default)
			)
			(layer "F.Fab")
		)
		(fp_line
			(start 0.12065 -0.3048)
			(end 0.67945 -0.3048)
			(stroke
				(width 0.1)
				(type default)
			)
			(layer "F.Fab")
		)
		(fp_line
			(start 0.12065 -0.2794)
			(end 0.12065 -0.3048)
			(stroke
				(width 0.1)
				(type default)
			)
			(layer "F.Fab")
		)
		(fp_line
			(start -0.12065 -0.2794)
			(end 0.12065 -0.2794)
			(stroke
				(width 0.1)
				(type default)
			)
			(layer "F.Fab")
		)
		(fp_line
			(start 0.120396 0.2794)
			(end -0.12065 0.2794)
			(stroke
				(width 0.1)
				(type default)
			)
			(layer "F.Fab")
		)
		(fp_line
			(start -0.12065 0.2794)
			(end -0.12065 0.3048)
			(stroke
				(width 0.1)
				(type default)
			)
			(layer "F.Fab")
		)
		(fp_line
			(start 0.67945 0.3048)
			(end 0.120396 0.3048)
			(stroke
				(width 0.1)
				(type default)
			)
			(layer "F.Fab")
		)
		(fp_line
			(start 0.120396 0.3048)
			(end 0.120396 0.2794)
			(stroke
				(width 0.1)
				(type default)
			)
			(layer "F.Fab")
		)
		(fp_line
			(start -0.12065 0.3048)
			(end -0.67945 0.3048)
			(stroke
				(width 0.1)
				(type default)
			)
			(layer "F.Fab")
		)
		(fp_line
			(start -0.67945 0.3048)
			(end -0.67945 -0.305054)
			(stroke
				(width 0.1)
				(type default)
			)
			(layer "F.Fab")
		)
		(pad "1" smd circle
			(at -0.40005 0 90)
			(size 0 0)
			(layers "F.Cu" "F.Mask" "F.Paste")
			(net "SMB_BIC_I2C9_MUX1_SSD13_R_SCL")
		)
		(pad "2" smd circle
			(at 0.40005 0 90)
			(size 0 0)
			(layers "F.Cu" "F.Mask" "F.Paste")
			(net "SMB_ISO_SSD13_SCL")
		)
	)
	(footprint ""
		(layer "F.Cu")
		(at 154.890724 -142.892018)
		(property "Reference" "R132"
			(at 0 0 0)
			(layer "F.SilkS")
			(hide yes)
			(effects
				(font
					(size 1.27 1.27)
				)
			)
		)
		(property "Value" ""
			(at 0 0 0)
			(layer "F.Fab")
			(effects
				(font
					(size 1.27 1.27)
				)
			)
		)
		(duplicate_pad_numbers_are_jumpers no)
		(fp_line
			(start -0.7874 -0.4064)
			(end 0.7874 -0.4064)
			(stroke
				(width 0.1524)
				(type default)
			)
			(layer "F.SilkS")
		)
		(fp_line
			(start -0.7874 0.4064)
			(end -0.7874 -0.4064)
			(stroke
				(width 0.1524)
				(type default)
			)
			(layer "F.SilkS")
		)
		(fp_line
			(start 0.7874 -0.4064)
			(end 0.7874 0.4064)
			(stroke
				(width 0.1524)
				(type default)
			)
			(layer "F.SilkS")
		)
		(fp_line
			(start 0.7874 0.4064)
			(end -0.7874 0.4064)
			(stroke
				(width 0.1524)
				(type default)
			)
			(layer "F.SilkS")
		)
		(fp_line
			(start -0.67945 -0.305054)
			(end -0.12065 -0.305054)
			(stroke
				(width 0.1)
				(type default)
			)
			(layer "F.Fab")
		)
		(fp_line
			(start -0.67945 0.3048)
			(end -0.67945 -0.305054)
			(stroke
				(width 0.1)
				(type default)
			)
			(layer "F.Fab")
		)
		(fp_line
			(start -0.12065 -0.305054)
			(end -0.12065 -0.2794)
			(stroke
				(width 0.1)
				(type default)
			)
			(layer "F.Fab")
		)
		(fp_line
			(start -0.12065 -0.2794)
			(end 0.12065 -0.2794)
			(stroke
				(width 0.1)
				(type default)
			)
			(layer "F.Fab")
		)
		(fp_line
			(start -0.12065 0.2794)
			(end -0.12065 0.3048)
			(stroke
				(width 0.1)
				(type default)
			)
			(layer "F.Fab")
		)
		(fp_line
			(start -0.12065 0.3048)
			(end -0.67945 0.3048)
			(stroke
				(width 0.1)
				(type default)
			)
			(layer "F.Fab")
		)
		(fp_line
			(start 0.120396 0.2794)
			(end -0.12065 0.2794)
			(stroke
				(width 0.1)
				(type default)
			)
			(layer "F.Fab")
		)
		(fp_line
			(start 0.120396 0.3048)
			(end 0.120396 0.2794)
			(stroke
				(width 0.1)
				(type default)
			)
			(layer "F.Fab")
		)
		(fp_line
			(start 0.12065 -0.3048)
			(end 0.67945 -0.3048)
			(stroke
				(width 0.1)
				(type default)
			)
			(layer "F.Fab")
		)
		(fp_line
			(start 0.12065 -0.2794)
			(end 0.12065 -0.3048)
			(stroke
				(width 0.1)
				(type default)
			)
			(layer "F.Fab")
		)
		(fp_line
			(start 0.67945 -0.3048)
			(end 0.67945 0.3048)
			(stroke
				(width 0.1)
				(type default)
			)
			(layer "F.Fab")
		)
		(fp_line
			(start 0.67945 0.3048)
			(end 0.120396 0.3048)
			(stroke
				(width 0.1)
				(type default)
			)
			(layer "F.Fab")
		)
		(pad "1" smd circle
			(at -0.40005 0)
			(size 0 0)
			(layers "F.Cu" "F.Mask" "F.Paste")
			(net "NIC2_BIF0_N")
		)
		(pad "2" smd circle
			(at 0.40005 0)
			(size 0 0)
			(layers "F.Cu" "F.Mask" "F.Paste")
			(net "GND")
		)
	)
	(footprint ""
		(layer "F.Cu")
		(at 354.875846 -36.915598 -90)
		(property "Reference" "R5568"
			(at 0 0 270)
			(layer "F.SilkS")
			(hide yes)
			(effects
				(font
					(size 1.27 1.27)
				)
			)
		)
		(property "Value" ""
			(at 0 0 270)
			(layer "F.Fab")
			(effects
				(font
					(size 1.27 1.27)
				)
			)
		)
		(duplicate_pad_numbers_are_jumpers no)
		(fp_line
			(start -0.7874 0.4064)
			(end -0.7874 -0.4064)
			(stroke
				(width 0.1524)
				(type default)
			)
			(layer "F.SilkS")
		)
		(fp_line
			(start 0.7874 0.4064)
			(end -0.7874 0.4064)
			(stroke
				(width 0.1524)
				(type default)
			)
			(layer "F.SilkS")
		)
		(fp_line
			(start -0.7874 -0.4064)
			(end 0.7874 -0.4064)
			(stroke
				(width 0.1524)
				(type default)
			)
			(layer "F.SilkS")
		)
		(fp_line
			(start 0.7874 -0.4064)
			(end 0.7874 0.4064)
			(stroke
				(width 0.1524)
				(type default)
			)
			(layer "F.SilkS")
		)
		(fp_line
			(start -0.67945 0.3048)
			(end -0.67945 -0.305054)
			(stroke
				(width 0.1)
				(type default)
			)
			(layer "F.Fab")
		)
		(fp_line
			(start -0.12065 0.3048)
			(end -0.67945 0.3048)
			(stroke
				(width 0.1)
				(type default)
			)
			(layer "F.Fab")
		)
		(fp_line
			(start 0.120396 0.3048)
			(end 0.120396 0.2794)
			(stroke
				(width 0.1)
				(type default)
			)
			(layer "F.Fab")
		)
		(fp_line
			(start 0.67945 0.3048)
			(end 0.120396 0.3048)
			(stroke
				(width 0.1)
				(type default)
			)
			(layer "F.Fab")
		)
		(fp_line
			(start -0.12065 0.2794)
			(end -0.12065 0.3048)
			(stroke
				(width 0.1)
				(type default)
			)
			(layer "F.Fab")
		)
		(fp_line
			(start 0.120396 0.2794)
			(end -0.12065 0.2794)
			(stroke
				(width 0.1)
				(type default)
			)
			(layer "F.Fab")
		)
		(fp_line
			(start -0.12065 -0.2794)
			(end 0.12065 -0.2794)
			(stroke
				(width 0.1)
				(type default)
			)
			(layer "F.Fab")
		)
		(fp_line
			(start 0.12065 -0.2794)
			(end 0.12065 -0.3048)
			(stroke
				(width 0.1)
				(type default)
			)
			(layer "F.Fab")
		)
		(fp_line
			(start 0.12065 -0.3048)
			(end 0.67945 -0.3048)
			(stroke
				(width 0.1)
				(type default)
			)
			(layer "F.Fab")
		)
		(fp_line
			(start 0.67945 -0.3048)
			(end 0.67945 0.3048)
			(stroke
				(width 0.1)
				(type default)
			)
			(layer "F.Fab")
		)
		(fp_line
			(start -0.67945 -0.305054)
			(end -0.12065 -0.305054)
			(stroke
				(width 0.1)
				(type default)
			)
			(layer "F.Fab")
		)
		(fp_line
			(start -0.12065 -0.305054)
			(end -0.12065 -0.2794)
			(stroke
				(width 0.1)
				(type default)
			)
			(layer "F.Fab")
		)
		(pad "1" smd circle
			(at -0.40005 0 270)
			(size 0 0)
			(layers "F.Cu" "F.Mask" "F.Paste")
			(net "PRSNT_SSD12_R1_N")
		)
		(pad "2" smd circle
			(at 0.40005 0 270)
			(size 0 0)
			(layers "F.Cu" "F.Mask" "F.Paste")
			(net "PRSNT_SSD12_R_N")
		)
	)
	(footprint ""
		(layer "F.Cu")
		(at 280.475182 -402.338032 -90)
		(property "Reference" "R1806"
			(at 0 0 270)
			(layer "F.SilkS")
			(hide yes)
			(effects
				(font
					(size 1.27 1.27)
				)
			)
		)
		(property "Value" ""
			(at 0 0 270)
			(layer "F.Fab")
			(effects
				(font
					(size 1.27 1.27)
				)
			)
		)
		(duplicate_pad_numbers_are_jumpers no)
		(fp_line
			(start -0.7874 0.4064)
			(end -0.7874 -0.4064)
			(stroke
				(width 0.1524)
				(type default)
			)
			(layer "F.SilkS")
		)
		(fp_line
			(start 0.7874 0.4064)
			(end -0.7874 0.4064)
			(stroke
				(width 0.1524)
				(type default)
			)
			(layer "F.SilkS")
		)
		(fp_line
			(start -0.7874 -0.4064)
			(end 0.7874 -0.4064)
			(stroke
				(width 0.1524)
				(type default)
			)
			(layer "F.SilkS")
		)
		(fp_line
			(start 0.7874 -0.4064)
			(end 0.7874 0.4064)
			(stroke
				(width 0.1524)
				(type default)
			)
			(layer "F.SilkS")
		)
		(fp_line
			(start -0.67945 0.3048)
			(end -0.67945 -0.305054)
			(stroke
				(width 0.1)
				(type default)
			)
			(layer "F.Fab")
		)
		(fp_line
			(start -0.12065 0.3048)
			(end -0.67945 0.3048)
			(stroke
				(width 0.1)
				(type default)
			)
			(layer "F.Fab")
		)
		(fp_line
			(start 0.120396 0.3048)
			(end 0.120396 0.2794)
			(stroke
				(width 0.1)
				(type default)
			)
			(layer "F.Fab")
		)
		(fp_line
			(start 0.67945 0.3048)
			(end 0.120396 0.3048)
			(stroke
				(width 0.1)
				(type default)
			)
			(layer "F.Fab")
		)
		(fp_line
			(start -0.12065 0.2794)
			(end -0.12065 0.3048)
			(stroke
				(width 0.1)
				(type default)
			)
			(layer "F.Fab")
		)
		(fp_line
			(start 0.120396 0.2794)
			(end -0.12065 0.2794)
			(stroke
				(width 0.1)
				(type default)
			)
			(layer "F.Fab")
		)
		(fp_line
			(start -0.12065 -0.2794)
			(end 0.12065 -0.2794)
			(stroke
				(width 0.1)
				(type default)
			)
			(layer "F.Fab")
		)
		(fp_line
			(start 0.12065 -0.2794)
			(end 0.12065 -0.3048)
			(stroke
				(width 0.1)
				(type default)
			)
			(layer "F.Fab")
		)
		(fp_line
			(start 0.12065 -0.3048)
			(end 0.67945 -0.3048)
			(stroke
				(width 0.1)
				(type default)
			)
			(layer "F.Fab")
		)
		(fp_line
			(start 0.67945 -0.3048)
			(end 0.67945 0.3048)
			(stroke
				(width 0.1)
				(type default)
			)
			(layer "F.Fab")
		)
		(fp_line
			(start -0.67945 -0.305054)
			(end -0.12065 -0.305054)
			(stroke
				(width 0.1)
				(type default)
			)
			(layer "F.Fab")
		)
		(fp_line
			(start -0.12065 -0.305054)
			(end -0.12065 -0.2794)
			(stroke
				(width 0.1)
				(type default)
			)
			(layer "F.Fab")
		)
		(pad "1" smd circle
			(at -0.40005 0 270)
			(size 0 0)
			(layers "F.Cu" "F.Mask" "F.Paste")
			(net "P3V3_AUX")
		)
		(pad "2" smd circle
			(at 0.40005 0 270)
			(size 0 0)
			(layers "F.Cu" "F.Mask" "F.Paste")
			(net "RST_MB_BIC_ISO_R_N")
		)
	)
	(footprint ""
		(layer "F.Cu")
		(at 321.698366 -297.46448)
		(property "Reference" "R3987"
			(at 0 0 0)
			(layer "F.SilkS")
			(hide yes)
			(effects
				(font
					(size 1.27 1.27)
				)
			)
		)
		(property "Value" ""
			(at 0 0 0)
			(layer "F.Fab")
			(effects
				(font
					(size 1.27 1.27)
				)
			)
		)
		(duplicate_pad_numbers_are_jumpers no)
		(fp_line
			(start -0.7874 -0.4064)
			(end 0.7874 -0.4064)
			(stroke
				(width 0.1524)
				(type default)
			)
			(layer "F.SilkS")
		)
		(fp_line
			(start -0.7874 0.4064)
			(end -0.7874 -0.4064)
			(stroke
				(width 0.1524)
				(type default)
			)
			(layer "F.SilkS")
		)
		(fp_line
			(start 0.7874 -0.4064)
			(end 0.7874 0.4064)
			(stroke
				(width 0.1524)
				(type default)
			)
			(layer "F.SilkS")
		)
		(fp_line
			(start 0.7874 0.4064)
			(end -0.7874 0.4064)
			(stroke
				(width 0.1524)
				(type default)
			)
			(layer "F.SilkS")
		)
		(fp_line
			(start -0.67945 -0.305054)
			(end -0.12065 -0.305054)
			(stroke
				(width 0.1)
				(type default)
			)
			(layer "F.Fab")
		)
		(fp_line
			(start -0.67945 0.3048)
			(end -0.67945 -0.305054)
			(stroke
				(width 0.1)
				(type default)
			)
			(layer "F.Fab")
		)
		(fp_line
			(start -0.12065 -0.305054)
			(end -0.12065 -0.2794)
			(stroke
				(width 0.1)
				(type default)
			)
			(layer "F.Fab")
		)
		(fp_line
			(start -0.12065 -0.2794)
			(end 0.12065 -0.2794)
			(stroke
				(width 0.1)
				(type default)
			)
			(layer "F.Fab")
		)
		(fp_line
			(start -0.12065 0.2794)
			(end -0.12065 0.3048)
			(stroke
				(width 0.1)
				(type default)
			)
			(layer "F.Fab")
		)
		(fp_line
			(start -0.12065 0.3048)
			(end -0.67945 0.3048)
			(stroke
				(width 0.1)
				(type default)
			)
			(layer "F.Fab")
		)
		(fp_line
			(start 0.120396 0.2794)
			(end -0.12065 0.2794)
			(stroke
				(width 0.1)
				(type default)
			)
			(layer "F.Fab")
		)
		(fp_line
			(start 0.120396 0.3048)
			(end 0.120396 0.2794)
			(stroke
				(width 0.1)
				(type default)
			)
			(layer "F.Fab")
		)
		(fp_line
			(start 0.12065 -0.3048)
			(end 0.67945 -0.3048)
			(stroke
				(width 0.1)
				(type default)
			)
			(layer "F.Fab")
		)
		(fp_line
			(start 0.12065 -0.2794)
			(end 0.12065 -0.3048)
			(stroke
				(width 0.1)
				(type default)
			)
			(layer "F.Fab")
		)
		(fp_line
			(start 0.67945 -0.3048)
			(end 0.67945 0.3048)
			(stroke
				(width 0.1)
				(type default)
			)
			(layer "F.Fab")
		)
		(fp_line
			(start 0.67945 0.3048)
			(end 0.120396 0.3048)
			(stroke
				(width 0.1)
				(type default)
			)
			(layer "F.Fab")
		)
		(pad "1" smd circle
			(at -0.40005 0)
			(size 0 0)
			(layers "F.Cu" "F.Mask" "F.Paste")
			(net "SMB_PEX2_HOST_LS_SDA")
		)
		(pad "2" smd circle
			(at 0.40005 0)
			(size 0 0)
			(layers "F.Cu" "F.Mask" "F.Paste")
			(net "I2C_PEX2_HOST_R_SDA")
		)
	)
)
